#ISCELL
  pure_quanta quanta_title_block_c *
  *
#ISCELL
  logical_power universal_gnd *
  page142_i1
#ISCELL
  standard offpage *
  page142_i10
#ISCELL
  standard offpage *
  page142_i11
#ISCELL
  standard offpage *
  page142_i12
#ISCELL
  standard offpage *
  page142_i13
#ISCELL
  standard offpage *
  page142_i14
#ISCELL
  standard offpage *
  page142_i15
#ISCELL
  standard offpage *
  page142_i16
#ISCELL
  standard offpage *
  page142_i17
#ISCELL
  standard offpage *
  page142_i18
#ISCELL
  standard offpage *
  page142_i19
#ISCELL
  standard offpage *
  page142_i2
#ISCELL
  standard offpage *
  page142_i20
#ISCELL
  standard offpage *
  page142_i21
#ISCELL
  standard offpage *
  page142_i22
#ISCELL
  standard offpage *
  page142_i23
#ISCELL
  standard offpage *
  page142_i24
#ISCELL
  standard offpage *
  page142_i25
#ISCELL
  standard offpage *
  page142_i26
#ISCELL
  standard offpage *
  page142_i27
#ISCELL
  standard offpage *
  page142_i28
#ISCELL
  standard offpage *
  page142_i29
#ISCELL
  standard offpage *
  page142_i3
#ISCELL
  standard offpage *
  page142_i30
#ISCELL
  standard offpage *
  page142_i31
#ISCELL
  standard offpage *
  page142_i32
#ISCELL
  standard offpage *
  page142_i33
#ISCELL
  logical_power universal_gnd *
  page142_i34
#ISCELL
  standard offpage *
  page142_i35
#ISCELL
  standard offpage *
  page142_i36
#ISCELL
  standard offpage *
  page142_i37
#ISCELL
  standard offpage *
  page142_i38
#ISCELL
  standard offpage *
  page142_i39
#ISCELL
  standard offpage *
  page142_i4
#ISCELL
  standard offpage *
  page142_i40
#ISCELL
  standard offpage *
  page142_i41
#ISCELL
  standard offpage *
  page142_i42
#ISCELL
  standard offpage *
  page142_i43
#ISCELL
  standard offpage *
  page142_i44
#ISCELL
  standard offpage *
  page142_i45
#ISCELL
  standard offpage *
  page142_i46
#ISCELL
  standard offpage *
  page142_i47
#ISCELL
  standard offpage *
  page142_i48
#ISCELL
  standard offpage *
  page142_i49
#ISCELL
  standard offpage *
  page142_i5
#ISCELL
  standard offpage *
  page142_i50
#ISCELL
  standard offpage *
  page142_i51
#ISCELL
  standard offpage *
  page142_i52
#ISCELL
  standard offpage *
  page142_i53
#ISCELL
  standard offpage *
  page142_i54
#ISCELL
  standard offpage *
  page142_i55
#ISCELL
  standard offpage *
  page142_i56
#ISCELL
  standard offpage *
  page142_i57
#ISCELL
  standard offpage *
  page142_i58
#ISCELL
  standard offpage *
  page142_i59
#ISCELL
  standard offpage *
  page142_i6
#ISCELL
  standard offpage *
  page142_i60
#ISCELL
  standard offpage *
  page142_i61
#ISCELL
  standard offpage *
  page142_i62
#ISCELL
  standard offpage *
  page142_i63
#ISCELL
  standard offpage *
  page142_i64
#CELL
  pure_quanta conn112_10137002101lf *
  page142_i65
#ISCELL
  standard offpage *
  page142_i66
#ISCELL
  standard offpage *
  page142_i67
#CELL
  pure_quanta conn112_10137002101lf *
  page142_i68
#ISCELL
  standard offpage *
  page142_i7
#ISCELL
  standard offpage *
  page142_i8
#ISCELL
  standard offpage *
  page142_i80
#ISCELL
  standard offpage *
  page142_i83
#ISCELL
  standard offpage *
  page142_i84
#ISCELL
  standard offpage *
  page142_i85
#ISCELL
  standard offpage *
  page142_i86
#ISCELL
  standard offpage *
  page142_i87
#ISCELL
  standard offpage *
  page142_i88
#ISCELL
  standard offpage *
  page142_i89
#ISCELL
  standard offpage *
  page142_i9
